(kicad_pcb
	(version 20241229)
	(generator "pcbnew")
	(generator_version "9.0")
	(general
		(thickness 1.6)
		(legacy_teardrops no)
	)
	(paper "A4")
	(title_block
		(title "OCuLink to PCIe adapter")
		(date "2025-06-18")
		(rev "1.0.0")
		(company "Antmicro Ltd")
		(comment 1 "www.antmicro.com")
		(comment 9 "footprints 50-51 of 159")
	)
	(layers
		(0 "F.Cu" signal)
		(4 "In1.Cu" signal)
		(6 "In2.Cu" signal)
		(2 "B.Cu" signal)
		(9 "F.Adhes" user "F.Adhesive")
		(11 "B.Adhes" user "B.Adhesive")
		(13 "F.Paste" user)
		(15 "B.Paste" user)
		(5 "F.SilkS" user "F.Silkscreen")
		(7 "B.SilkS" user "B.Silkscreen")
		(1 "F.Mask" user)
		(3 "B.Mask" user)
		(17 "Dwgs.User" user "User.Drawings")
		(19 "Cmts.User" user "User.Comments")
		(21 "Eco1.User" user "User.Eco1")
		(23 "Eco2.User" user "User.Eco2")
		(25 "Edge.Cuts" user)
		(27 "Margin" user)
		(31 "F.CrtYd" user "F.Courtyard")
		(29 "B.CrtYd" user "B.Courtyard")
		(35 "F.Fab" user)
		(33 "B.Fab" user)
	)
	(footprint "antmicro-footprints:Amphenol_G14A421211112HR"
		(locked yes)
		(layer "F.Cu")
		(at 127.05 36 180)
		(property "Reference" "J1"
			(at -6.35 -6.2 180)
			(layer "F.SilkS")
			(effects
				(font
					(size 0.7 0.7)
					(thickness 0.15)
				)
				(justify left bottom)
			)
		)
		(property "Value" "OCuLink_x4_Amphenol_G14A421211112HR_CUSTOM_device_side"
			(at 0 6.385 180)
			(unlocked yes)
			(layer "F.Fab")
			(effects
				(font
					(size 0.7 0.7)
					(thickness 0.15)
				)
				(justify left bottom)
			)
		)
		(property "Datasheet" "https://cdn.amphenol-cs.com/media/wysiwyg/files/drawing/g14a421x1bxxxhr.pdf"
			(at 0 0 0)
			(layer "F.Fab")
			(hide yes)
			(effects
				(font
					(size 1.27 1.27)
					(thickness 0.15)
				)
			)
		)
		(property "Description" "I/O Connectors OCulink, Receptacle, 0.5mm pitch, 4X, R/A SMT with shell leg SMT type, 30U\" gold plating, LCP, black, T&R packing"
			(at 0 0 0)
			(layer "F.Fab")
			(hide yes)
			(effects
				(font
					(size 1.27 1.27)
					(thickness 0.15)
				)
			)
		)
		(property "Manufacturer" "Amphenol"
			(at 0 0 180)
			(unlocked yes)
			(layer "F.Fab")
			(hide yes)
			(effects
				(font
					(size 1 1)
					(thickness 0.15)
				)
			)
		)
		(property "MPN" "G14A421211112HR"
			(at 0 0 180)
			(unlocked yes)
			(layer "F.Fab")
			(hide yes)
			(effects
				(font
					(size 1 1)
					(thickness 0.15)
				)
			)
		)
		(property "Author" "Antmicro"
			(at 0 0 180)
			(unlocked yes)
			(layer "F.Fab")
			(hide yes)
			(effects
				(font
					(size 1 1)
					(thickness 0.15)
				)
			)
		)
		(property "License" "Apache-2.0"
			(at 0 0 180)
			(unlocked yes)
			(layer "F.Fab")
			(hide yes)
			(effects
				(font
					(size 1 1)
					(thickness 0.15)
				)
			)
		)
		(sheetname "/OCuLink/")
		(sheetfile "oculink.kicad_sch")
		(solder_paste_margin -0.06)
		(attr smd)
		(fp_line
			(start 6.8 -3)
			(end 6.8 -0.4)
			(stroke
				(width 0.1)
				(type default)
			)
			(layer "F.SilkS")
		)
		(fp_line
			(start -6.8 -0.4)
			(end -6.8 -3)
			(stroke
				(width 0.1)
				(type default)
			)
			(layer "F.SilkS")
		)
		(fp_circle
			(center -5.3 -5.52)
			(end -5.25 -5.52)
			(stroke
				(width 0.15)
				(type solid)
			)
			(fill yes)
			(layer "F.SilkS")
		)
		(fp_rect
			(start -8.22 -5.22)
			(end 8.22 4.94)
			(stroke
				(width 0.05)
				(type solid)
			)
			(fill no)
			(layer "F.CrtYd")
		)
		(fp_line
			(start 7 3.065)
			(end -7 3.065)
			(stroke
				(width 0.1)
				(type default)
			)
			(layer "F.Fab")
		)
		(fp_text user "Author: Antmicro"
			(at -8.22 11.085 0)
			(layer "F.Fab")
			(effects
				(font
					(size 0.7 0.7)
					(thickness 0.15)
				)
				(justify right top)
			)
		)
		(fp_text user "License: Apache-2.0"
			(at -8.22 12.285 0)
			(layer "F.Fab")
			(effects
				(font
					(size 0.7 0.7)
					(thickness 0.15)
				)
				(justify right top)
			)
		)
		(fp_text user "PCB EDGE"
			(at 2.8 2.95 180)
			(unlocked yes)
			(layer "F.Fab")
			(effects
				(font
					(size 0.5 0.5)
					(thickness 0.125)
				)
				(justify left bottom)
			)
		)
		(fp_text user "${REFERENCE}"
			(at 0 -0.34 180)
			(layer "F.Fab")
			(effects
				(font
					(size 0.7 0.7)
					(thickness 0.15)
				)
				(justify left bottom)
			)
		)
		(pad "" np_thru_hole circle
			(at -5.42 -1.395 270)
			(size 1 1)
			(drill 1)
			(layers "F&B.Cu" "*.Mask")
		)
		(pad "" np_thru_hole circle
			(at 5.95 -1.395 270)
			(size 1 1)
			(drill 1)
			(layers "F&B.Cu" "*.Mask")
		)
		(pad "A1" smd roundrect
			(at -4.75 -2.115 270)
			(size 0.91 0.31)
			(layers "F.Cu" "F.Mask" "F.Paste")
			(roundrect_rratio 0.5)
			(net 92 "unconnected-(J1-V_{ACT}_RX_3V3-PadA1)")
			(pinfunction "V_{ACT}_RX_3V3")
			(pintype "power_in+no_connect")
		)
		(pad "A2" smd roundrect
			(at -4.25 -2.115 270)
			(size 0.91 0.31)
			(layers "F.Cu" "F.Mask" "F.Paste")
			(roundrect_rratio 0.5)
			(net 66 "GND")
			(pinfunction "GND")
			(pintype "passive")
		)
		(pad "A3" smd roundrect
			(at -3.75 -2.115 270)
			(size 0.91 0.31)
			(layers "F.Cu" "F.Mask" "F.Paste")
			(roundrect_rratio 0.5)
			(net 72 "/OCuLink/PCIe_{x4}.TX0+")
			(pinfunction "PER0+")
			(pintype "output")
		)
		(pad "A4" smd roundrect
			(at -3.25 -2.115 270)
			(size 0.91 0.31)
			(layers "F.Cu" "F.Mask" "F.Paste")
			(roundrect_rratio 0.5)
			(net 74 "/OCuLink/PCIe_{x4}.TX0-")
			(pinfunction "PER0-")
			(pintype "output")
		)
		(pad "A5" smd roundrect
			(at -2.75 -2.115 270)
			(size 0.91 0.31)
			(layers "F.Cu" "F.Mask" "F.Paste")
			(roundrect_rratio 0.5)
			(net 66 "GND")
			(pinfunction "GND")
			(pintype "passive")
		)
		(pad "A6" smd roundrect
			(at -2.25 -2.115 270)
			(size 0.91 0.31)
			(layers "F.Cu" "F.Mask" "F.Paste")
			(roundrect_rratio 0.5)
			(net 77 "/OCuLink/PCIe_{x4}.TX1+")
			(pinfunction "PER1+")
			(pintype "output")
		)
		(pad "A7" smd roundrect
			(at -1.75 -2.115 270)
			(size 0.91 0.31)
			(layers "F.Cu" "F.Mask" "F.Paste")
			(roundrect_rratio 0.5)
			(net 69 "/OCuLink/PCIe_{x4}.TX1-")
			(pinfunction "PER1-")
			(pintype "output")
		)
		(pad "A8" smd roundrect
			(at -1.25 -2.115 270)
			(size 0.91 0.31)
			(layers "F.Cu" "F.Mask" "F.Paste")
			(roundrect_rratio 0.5)
			(net 66 "GND")
			(pinfunction "GND")
			(pintype "passive")
		)
		(pad "A9" smd roundrect
			(at -0.75 -2.115 270)
			(size 0.91 0.31)
			(layers "F.Cu" "F.Mask" "F.Paste")
			(roundrect_rratio 0.5)
			(net 101 "/OCuLink/I2C0C_SCL")
			(pinfunction "SCL")
			(pintype "bidirectional")
		)
		(pad "A10" smd roundrect
			(at -0.25 -2.115 270)
			(size 0.91 0.31)
			(layers "F.Cu" "F.Mask" "F.Paste")
			(roundrect_rratio 0.5)
			(net 95 "/OCuLink/I2C0C_SDA")
			(pinfunction "SDA")
			(pintype "bidirectional")
		)
		(pad "A11" smd roundrect
			(at 0.25 -2.115 270)
			(size 0.91 0.31)
			(layers "F.Cu" "F.Mask" "F.Paste")
			(roundrect_rratio 0.5)
			(net 66 "GND")
			(pinfunction "GND")
			(pintype "passive")
		)
		(pad "A12" smd roundrect
			(at 0.75 -2.115 270)
			(size 0.91 0.31)
			(layers "F.Cu" "F.Mask" "F.Paste")
			(roundrect_rratio 0.5)
			(net 183 "/OCuLink/~{PERSTC}")
			(pinfunction "~{PERST}")
			(pintype "bidirectional")
		)
		(pad "A13" smd roundrect
			(at 1.25 -2.115 270)
			(size 0.91 0.31)
			(layers "F.Cu" "F.Mask" "F.Paste")
			(roundrect_rratio 0.5)
			(net 182 "/OCuLink/~{CPRSNTC}")
			(pinfunction "~{CPRSNT}")
			(pintype "bidirectional")
		)
		(pad "A14" smd roundrect
			(at 1.75 -2.115 270)
			(size 0.91 0.31)
			(layers "F.Cu" "F.Mask" "F.Paste")
			(roundrect_rratio 0.5)
			(net 66 "GND")
			(pinfunction "GND")
			(pintype "passive")
		)
		(pad "A15" smd roundrect
			(at 2.25 -2.115 270)
			(size 0.91 0.31)
			(layers "F.Cu" "F.Mask" "F.Paste")
			(roundrect_rratio 0.5)
			(net 70 "/OCuLink/PCIe_{x4}.TX2+")
			(pinfunction "PER2+")
			(pintype "output")
		)
		(pad "A16" smd roundrect
			(at 2.75 -2.115 270)
			(size 0.91 0.31)
			(layers "F.Cu" "F.Mask" "F.Paste")
			(roundrect_rratio 0.5)
			(net 76 "/OCuLink/PCIe_{x4}.TX2-")
			(pinfunction "PER2-")
			(pintype "output")
		)
		(pad "A17" smd roundrect
			(at 3.25 -2.115 270)
			(size 0.91 0.31)
			(layers "F.Cu" "F.Mask" "F.Paste")
			(roundrect_rratio 0.5)
			(net 66 "GND")
			(pinfunction "GND")
			(pintype "passive")
		)
		(pad "A18" smd roundrect
			(at 3.75 -2.115 270)
			(size 0.91 0.31)
			(layers "F.Cu" "F.Mask" "F.Paste")
			(roundrect_rratio 0.5)
			(net 82 "/OCuLink/PCIe_{x4}.TX3+")
			(pinfunction "PER3+")
			(pintype "output")
		)
		(pad "A19" smd roundrect
			(at 4.25 -2.115 270)
			(size 0.91 0.31)
			(layers "F.Cu" "F.Mask" "F.Paste")
			(roundrect_rratio 0.5)
			(net 80 "/OCuLink/PCIe_{x4}.TX3-")
			(pinfunction "PER3-")
			(pintype "output")
		)
		(pad "A20" smd roundrect
			(at 4.75 -2.115 270)
			(size 0.91 0.31)
			(layers "F.Cu" "F.Mask" "F.Paste")
			(roundrect_rratio 0.5)
			(net 66 "GND")
			(pinfunction "GND")
			(pintype "passive")
		)
		(pad "A21" smd roundrect
			(at 5.25 -2.115 270)
			(size 0.91 0.31)
			(layers "F.Cu" "F.Mask" "F.Paste")
			(roundrect_rratio 0.5)
			(net 100 "unconnected-(J1-5V-PadA21)_1")
			(pinfunction "5V")
			(pintype "passive+no_connect")
		)
		(pad "B1" smd roundrect
			(at -5.25 -4.305 270)
			(size 0.91 0.31)
			(layers "F.Cu" "F.Mask" "F.Paste")
			(roundrect_rratio 0.5)
			(net 98 "unconnected-(J1-5V-PadA21)")
			(pinfunction "5V")
			(pintype "passive+no_connect")
		)
		(pad "B2" smd roundrect
			(at -4.75 -4.305 270)
			(size 0.91 0.31)
			(layers "F.Cu" "F.Mask" "F.Paste")
			(roundrect_rratio 0.5)
			(net 66 "GND")
			(pinfunction "GND")
			(pintype "passive")
		)
		(pad "B3" smd roundrect
			(at -4.25 -4.305 270)
			(size 0.91 0.31)
			(layers "F.Cu" "F.Mask" "F.Paste")
			(roundrect_rratio 0.5)
			(net 78 "/OCuLink/PCIe_{x4}.RX0+")
			(pinfunction "PET0+")
			(pintype "input")
		)
		(pad "B4" smd roundrect
			(at -3.75 -4.305 270)
			(size 0.91 0.31)
			(layers "F.Cu" "F.Mask" "F.Paste")
			(roundrect_rratio 0.5)
			(net 73 "/OCuLink/PCIe_{x4}.RX0-")
			(pinfunction "PET0-")
			(pintype "input")
		)
		(pad "B5" smd roundrect
			(at -3.25 -4.305 270)
			(size 0.91 0.31)
			(layers "F.Cu" "F.Mask" "F.Paste")
			(roundrect_rratio 0.5)
			(net 66 "GND")
			(pinfunction "GND")
			(pintype "passive")
		)
		(pad "B6" smd roundrect
			(at -2.75 -4.305 270)
			(size 0.91 0.31)
			(layers "F.Cu" "F.Mask" "F.Paste")
			(roundrect_rratio 0.5)
			(net 75 "/OCuLink/PCIe_{x4}.RX1+")
			(pinfunction "PET1+")
			(pintype "input")
		)
		(pad "B7" smd roundrect
			(at -2.25 -4.305 270)
			(size 0.91 0.31)
			(layers "F.Cu" "F.Mask" "F.Paste")
			(roundrect_rratio 0.5)
			(net 71 "/OCuLink/PCIe_{x4}.RX1-")
			(pinfunction "PET1-")
			(pintype "input")
		)
		(pad "B8" smd roundrect
			(at -1.75 -4.305 270)
			(size 0.91 0.31)
			(layers "F.Cu" "F.Mask" "F.Paste")
			(roundrect_rratio 0.5)
			(net 66 "GND")
			(pinfunction "GND")
			(pintype "passive")
		)
		(pad "B9" smd roundrect
			(at -1.25 -4.305 270)
			(size 0.91 0.31)
			(layers "F.Cu" "F.Mask" "F.Paste")
			(roundrect_rratio 0.5)
			(net 112 "unconnected-(J1-NC-PadB9)")
			(pinfunction "NC")
			(pintype "no_connect")
		)
		(pad "B10" smd roundrect
			(at -0.75 -4.305 270)
			(size 0.91 0.31)
			(layers "F.Cu" "F.Mask" "F.Paste")
			(roundrect_rratio 0.5)
			(net 184 "/OCuLink/~{WAKEC}")
			(pinfunction "~{CWAKE}")
			(pintype "bidirectional")
		)
		(pad "B11" smd roundrect
			(at -0.25 -4.305 270)
			(size 0.91 0.31)
			(layers "F.Cu" "F.Mask" "F.Paste")
			(roundrect_rratio 0.5)
			(net 66 "GND")
			(pinfunction "GND")
			(pintype "passive")
		)
		(pad "B12" smd roundrect
			(at 0.25 -4.305 270)
			(size 0.91 0.31)
			(layers "F.Cu" "F.Mask" "F.Paste")
			(roundrect_rratio 0.5)
			(net 170 "/OCuLink/PCIe_{REF0}_R.CK+")
			(pinfunction "VSP1")
			(pintype "bidirectional")
		)
		(pad "B13" smd roundrect
			(at 0.75 -4.305 270)
			(size 0.91 0.31)
			(layers "F.Cu" "F.Mask" "F.Paste")
			(roundrect_rratio 0.5)
			(net 171 "/OCuLink/PCIe_{REF0}_R.CK-")
			(pinfunction "VSP2")
			(pintype "bidirectional")
		)
		(pad "B14" smd roundrect
			(at 1.25 -4.305 270)
			(size 0.91 0.31)
			(layers "F.Cu" "F.Mask" "F.Paste")
			(roundrect_rratio 0.5)
			(net 66 "GND")
			(pinfunction "GND")
			(pintype "passive")
		)
		(pad "B15" smd roundrect
			(at 1.75 -4.305 270)
			(size 0.91 0.31)
			(layers "F.Cu" "F.Mask" "F.Paste")
			(roundrect_rratio 0.5)
			(net 81 "/OCuLink/PCIe_{x4}.RX2+")
			(pinfunction "PET2+")
			(pintype "input")
		)
		(pad "B16" smd roundrect
			(at 2.25 -4.305 270)
			(size 0.91 0.31)
			(layers "F.Cu" "F.Mask" "F.Paste")
			(roundrect_rratio 0.5)
			(net 79 "/OCuLink/PCIe_{x4}.RX2-")
			(pinfunction "PET2-")
			(pintype "input")
		)
		(pad "B17" smd roundrect
			(at 2.75 -4.305 270)
			(size 0.91 0.31)
			(layers "F.Cu" "F.Mask" "F.Paste")
			(roundrect_rratio 0.5)
			(net 66 "GND")
			(pinfunction "GND")
			(pintype "passive")
		)
		(pad "B18" smd roundrect
			(at 3.25 -4.305 270)
			(size 0.91 0.31)
			(layers "F.Cu" "F.Mask" "F.Paste")
			(roundrect_rratio 0.5)
			(net 68 "/OCuLink/PCIe_{x4}.RX3+")
			(pinfunction "PET3+")
			(pintype "input")
		)
		(pad "B19" smd roundrect
			(at 3.75 -4.305 270)
			(size 0.91 0.31)
			(layers "F.Cu" "F.Mask" "F.Paste")
			(roundrect_rratio 0.5)
			(net 67 "/OCuLink/PCIe_{x4}.RX3-")
			(pinfunction "PET3-")
			(pintype "input")
		)
		(pad "B20" smd roundrect
			(at 4.25 -4.305 270)
			(size 0.91 0.31)
			(layers "F.Cu" "F.Mask" "F.Paste")
			(roundrect_rratio 0.5)
			(net 66 "GND")
			(pinfunction "GND")
			(pintype "passive")
		)
		(pad "B21" smd roundrect
			(at 4.75 -4.305 270)
			(size 0.91 0.31)
			(layers "F.Cu" "F.Mask" "F.Paste")
			(roundrect_rratio 0.5)
			(net 94 "unconnected-(J1-V_{ACT}_TX_3V3-PadB21)")
			(pinfunction "V_{ACT}_TX_3V3")
			(pintype "power_in+no_connect")
		)
		(pad "SH" smd roundrect
			(at -6.91 -3.915 270)
			(size 1.38 1.81)
			(layers "F.Cu" "F.Mask" "F.Paste")
			(roundrect_rratio 0.1)
			(net 66 "GND")
			(pinfunction "SH")
			(pintype "passive")
		)
		(pad "SH" smd roundrect
			(at -6.91 0.805 270)
			(size 1.81 1.8)
			(layers "F.Cu" "F.Mask" "F.Paste")
			(roundrect_rratio 0.1)
			(net 66 "GND")
			(pinfunction "SH")
			(pintype "passive")
		)
		(pad "SH" smd roundrect
			(at 6.91 -3.915 270)
			(size 1.38 1.81)
			(layers "F.Cu" "F.Mask" "F.Paste")
			(roundrect_rratio 0.1)
			(net 66 "GND")
			(pinfunction "SH")
			(pintype "passive")
		)
		(pad "SH" smd roundrect
			(at 6.91 0.805 270)
			(size 1.81 1.8)
			(layers "F.Cu" "F.Mask" "F.Paste")
			(roundrect_rratio 0.1)
			(net 66 "GND")
			(pinfunction "SH")
			(pintype "passive")
		)
	)
	(footprint "antmicro-footprints:R_0402_1005Metric"
		(layer "F.Cu")
		(at 148.151999 89)
		(descr "Resistor SMD 0402")
		(tags "resistor SMD 0402")
		(property "Reference" "R23"
			(at 1.248001 0.3 180)
			(layer "F.SilkS")
			(effects
				(font
					(size 0.7 0.7)
					(thickness 0.15)
				)
				(justify left bottom)
			)
		)
		(property "Value" "R_2k_0402"
			(at -1.011843 1.772046 0)
			(layer "F.Fab")
			(effects
				(font
					(size 0.7 0.7)
					(thickness 0.15)
				)
				(justify left bottom)
			)
		)
		(property "Datasheet" "https://www.bourns.com/docs/product-datasheets/cr.pdf"
			(at 0 0 0)
			(layer "F.Fab")
			(hide yes)
			(effects
				(font
					(size 1.27 1.27)
					(thickness 0.15)
				)
			)
		)
		(property "Description" "SMD Chip Resistor, 2 kohm, ± 1%, 62.5 mW, 0402 [1005 Metric], Thick Film, General Purpose"
			(at 0 0 0)
			(layer "F.Fab")
			(hide yes)
			(effects
				(font
					(size 1.27 1.27)
					(thickness 0.15)
				)
			)
		)
		(property "Manufacturer" "Bourns"
			(at 0 0 0)
			(unlocked yes)
			(layer "F.Fab")
			(hide yes)
			(effects
				(font
					(size 1 1)
					(thickness 0.15)
				)
			)
		)
		(property "MPN" "CR0402-FX-2001GLF"
			(at 0 0 0)
			(unlocked yes)
			(layer "F.Fab")
			(hide yes)
			(effects
				(font
					(size 1 1)
					(thickness 0.15)
				)
			)
		)
		(property "Val" "2k"
			(at 0 0 0)
			(unlocked yes)
			(layer "F.Fab")
			(hide yes)
			(effects
				(font
					(size 1 1)
					(thickness 0.15)
				)
			)
		)
		(property "License" "Apache-2.0"
			(at 0 0 0)
			(unlocked yes)
			(layer "F.Fab")
			(hide yes)
			(effects
				(font
					(size 1 1)
					(thickness 0.15)
				)
			)
		)
		(property "Author" "Antmicro"
			(at 0 0 0)
			(unlocked yes)
			(layer "F.Fab")
			(hide yes)
			(effects
				(font
					(size 1 1)
					(thickness 0.15)
				)
			)
		)
		(property "Tolerance" "1%"
			(at 0 0 0)
			(unlocked yes)
			(layer "F.Fab")
			(hide yes)
			(effects
				(font
					(size 1 1)
					(thickness 0.15)
				)
			)
		)
		(sheetname "/USB-PD/")
		(sheetfile "usb-pd.kicad_sch")
		(attr smd)
		(fp_rect
			(start -0.925 -0.47)
			(end 0.925 0.47)
			(stroke
				(width 0.05)
				(type default)
			)
			(fill no)
			(layer "F.CrtYd")
		)
		(fp_rect
			(start -0.5 -0.25)
			(end 0.5 0.25)
			(stroke
				(width 0.15)
				(type solid)
			)
			(fill no)
			(layer "F.Fab")
		)
		(fp_text user "${REFERENCE}"
			(at 0 0 0)
			(layer "F.Fab")
			(effects
				(font
					(size 0.7 0.7)
					(thickness 0.15)
				)
				(justify left bottom)
			)
		)
		(fp_text user "License: Apache-2.0"
			(at -0.949999 5.169 0)
			(layer "F.Fab")
			(effects
				(font
					(size 0.7 0.7)
					(thickness 0.15)
				)
				(justify left bottom)
			)
		)
		(fp_text user "Author: Antmicro"
			(at -0.95 4.169 0)
			(layer "F.Fab")
			(effects
				(font
					(size 0.7 0.7)
					(thickness 0.15)
				)
				(justify left bottom)
			)
		)
		(pad "1" smd roundrect
			(at -0.48 0)
			(size 0.59 0.64)
			(layers "F.Cu" "F.Mask" "F.Paste")
			(roundrect_rratio 0.25)
			(net 153 "/USB-PD/12V_MODE")
			(pintype "passive")
		)
		(pad "2" smd roundrect
			(at 0.48 0)
			(size 0.59 0.64)
			(layers "F.Cu" "F.Mask" "F.Paste")
			(roundrect_rratio 0.25)
			(net 66 "GND")
			(pintype "passive")
		)
	)
)
